# T6G (Grand Teton) — schematic netlist excerpt (pin names and nets, part order shuffled) for the footprints in the layout excerpt that follows; sources: Cadence DE-HDL packaged netlist, KiCad conversion of 04192023_DAF0TMB3IC0_F0TG_MB_C_brd_V02_OCP.brd

R605  Q_RES  49.9 1% CHIP  pkg 0402LF  page 77 : A = SPI_CPU0_LVC3_D1 ; B = SPI_CPU0_LVC3_SCM_D1
R4556  Q_RES  33.2 1% CHIP  pkg 0402LF  page 81 : A = HGX_DETECT_N_R ; B = HGX_DETECT_N
C944  Q_CAP_DIFFBUS  DIFF BUS_0.22UF 6.3V 20% X6S  pkg C0201  page 63 : \1\ = P5E_CPU0_P1_TX_C_DN<10> ; \2\ = P5E_CPU0_P1_TX_DN<10>

(kicad_pcb
	(version 20260206)
	(generator "pcbnew")
	(generator_version "10.0")
	(general
		(thickness 1.6)
		(legacy_teardrops no)
	)
	(paper "A4")
	(title_block
		(title "04192023_DAF0TMB3IC0_F0TG_MB_C_brd_V02_OCP.brd")
		(comment 1 "Grand Teton / footprints 3363-3365 of 8354")
	)
	(layers
		(0 "F.Cu" signal "TOP")
		(4 "In1.Cu" signal "GND")
		(6 "In2.Cu" signal "IN1")
		(8 "In3.Cu" signal "GND1")
		(10 "In4.Cu" signal "IN2")
		(12 "In5.Cu" signal "GND2")
		(14 "In6.Cu" signal "IN3")
		(16 "In7.Cu" signal "GND3")
		(18 "In8.Cu" signal "VCC")
		(20 "In9.Cu" signal "VCC1")
		(22 "In10.Cu" signal "GND4")
		(24 "In11.Cu" signal "IN4")
		(26 "In12.Cu" signal "GND5")
		(28 "In13.Cu" signal "IN5")
		(30 "In14.Cu" signal "GND6")
		(32 "In15.Cu" signal "IN6")
		(34 "In16.Cu" signal "GND7")
		(2 "B.Cu" signal "BOTTOM")
		(9 "F.Adhes" user "F.Adhesive")
		(11 "B.Adhes" user "B.Adhesive")
		(13 "F.Paste" user "Package Geometry/Pastemask Top")
		(15 "B.Paste" user "Package Geometry/Pastemask Bottom")
		(5 "F.SilkS" user "Ref Des/Silkscreen Top")
		(7 "B.SilkS" user "Ref Des/Silkscreen Bottom")
		(1 "F.Mask" user "Board Geometry/Soldermask Top")
		(3 "B.Mask" user "Board Geometry/Soldermask Bottom")
		(17 "Dwgs.User" user "User.Drawings")
		(19 "Cmts.User" user "User.Comments")
		(21 "Eco1.User" user "User.Eco1")
		(23 "Eco2.User" user "User.Eco2")
		(25 "Edge.Cuts" user "Board Geometry/Outline")
		(27 "Margin" user)
		(31 "F.CrtYd" user "Package Geometry/Place Bound Top")
		(29 "B.CrtYd" user "Package Geometry/Place Bound Bottom")
		(35 "F.Fab" user "Ref Des/Assembly Top")
		(33 "B.Fab" user "Ref Des/Assembly Bottom")
	)
	(footprint ""
		(layer "F.Cu")
		(at 351.151444 -383.88163 -90)
		(property "Reference" "C944"
			(at 0 0 270)
			(layer "F.SilkS")
			(hide yes)
			(effects
				(font
					(size 1.27 1.27)
				)
			)
		)
		(property "Value" ""
			(at 0 0 270)
			(layer "F.Fab")
			(effects
				(font
					(size 1.27 1.27)
				)
			)
		)
		(duplicate_pad_numbers_are_jumpers no)
		(fp_line
			(start -0.299974 0.150114)
			(end -0.299974 -0.150114)
			(stroke
				(width 0.1)
				(type default)
			)
			(layer "F.Fab")
		)
		(fp_line
			(start 0.299974 0.150114)
			(end -0.299974 0.150114)
			(stroke
				(width 0.1)
				(type default)
			)
			(layer "F.Fab")
		)
		(fp_line
			(start -0.299974 -0.150114)
			(end 0.299974 -0.150114)
			(stroke
				(width 0.1)
				(type default)
			)
			(layer "F.Fab")
		)
		(fp_line
			(start 0.299974 -0.150114)
			(end 0.299974 0.150114)
			(stroke
				(width 0.1)
				(type default)
			)
			(layer "F.Fab")
		)
		(pad "1" smd rect
			(at -0.2667 0 270)
			(size 0.3048 0.381)
			(layers "F.Cu" "F.Mask" "F.Paste")
			(net "P5E_CPU0_P1_TX_C_DN<10>")
		)
		(pad "2" smd rect
			(at 0.2667 0 270)
			(size 0.3048 0.381)
			(layers "F.Cu" "F.Mask" "F.Paste")
			(net "P5E_CPU0_P1_TX_DN<10>")
		)
	)
	(footprint ""
		(layer "F.Cu")
		(at 205.159356 -114.249708)
		(property "Reference" "R4556"
			(at 0 0 0)
			(layer "F.SilkS")
			(hide yes)
			(effects
				(font
					(size 1.27 1.27)
				)
			)
		)
		(property "Value" ""
			(at 0 0 0)
			(layer "F.Fab")
			(effects
				(font
					(size 1.27 1.27)
				)
			)
		)
		(duplicate_pad_numbers_are_jumpers no)
		(fp_line
			(start -0.7874 -0.4064)
			(end 0.7874 -0.4064)
			(stroke
				(width 0.1524)
				(type default)
			)
			(layer "F.SilkS")
		)
		(fp_line
			(start -0.7874 0.4064)
			(end -0.7874 -0.4064)
			(stroke
				(width 0.1524)
				(type default)
			)
			(layer "F.SilkS")
		)
		(fp_line
			(start 0.7874 -0.4064)
			(end 0.7874 0.4064)
			(stroke
				(width 0.1524)
				(type default)
			)
			(layer "F.SilkS")
		)
		(fp_line
			(start 0.7874 0.4064)
			(end -0.7874 0.4064)
			(stroke
				(width 0.1524)
				(type default)
			)
			(layer "F.SilkS")
		)
		(fp_line
			(start -0.67945 -0.305054)
			(end -0.12065 -0.305054)
			(stroke
				(width 0.1)
				(type default)
			)
			(layer "F.Fab")
		)
		(fp_line
			(start -0.67945 0.3048)
			(end -0.67945 -0.305054)
			(stroke
				(width 0.1)
				(type default)
			)
			(layer "F.Fab")
		)
		(fp_line
			(start -0.12065 -0.305054)
			(end -0.12065 -0.2794)
			(stroke
				(width 0.1)
				(type default)
			)
			(layer "F.Fab")
		)
		(fp_line
			(start -0.12065 -0.2794)
			(end 0.12065 -0.2794)
			(stroke
				(width 0.1)
				(type default)
			)
			(layer "F.Fab")
		)
		(fp_line
			(start -0.12065 0.2794)
			(end -0.12065 0.3048)
			(stroke
				(width 0.1)
				(type default)
			)
			(layer "F.Fab")
		)
		(fp_line
			(start -0.12065 0.3048)
			(end -0.67945 0.3048)
			(stroke
				(width 0.1)
				(type default)
			)
			(layer "F.Fab")
		)
		(fp_line
			(start 0.120396 0.2794)
			(end -0.12065 0.2794)
			(stroke
				(width 0.1)
				(type default)
			)
			(layer "F.Fab")
		)
		(fp_line
			(start 0.120396 0.3048)
			(end 0.120396 0.2794)
			(stroke
				(width 0.1)
				(type default)
			)
			(layer "F.Fab")
		)
		(fp_line
			(start 0.12065 -0.3048)
			(end 0.67945 -0.3048)
			(stroke
				(width 0.1)
				(type default)
			)
			(layer "F.Fab")
		)
		(fp_line
			(start 0.12065 -0.2794)
			(end 0.12065 -0.3048)
			(stroke
				(width 0.1)
				(type default)
			)
			(layer "F.Fab")
		)
		(fp_line
			(start 0.67945 -0.3048)
			(end 0.67945 0.3048)
			(stroke
				(width 0.1)
				(type default)
			)
			(layer "F.Fab")
		)
		(fp_line
			(start 0.67945 0.3048)
			(end 0.120396 0.3048)
			(stroke
				(width 0.1)
				(type default)
			)
			(layer "F.Fab")
		)
		(pad "1" smd circle
			(at -0.40005 0)
			(size 0 0)
			(layers "F.Cu" "F.Mask" "F.Paste")
			(net "HGX_DETECT_N_R")
		)
		(pad "2" smd circle
			(at 0.40005 0)
			(size 0 0)
			(layers "F.Cu" "F.Mask" "F.Paste")
			(net "HGX_DETECT_N")
		)
	)
	(footprint ""
		(layer "F.Cu")
		(at 260.340094 -141.968728 90)
		(property "Reference" "R605"
			(at 0 0 90)
			(layer "F.SilkS")
			(hide yes)
			(effects
				(font
					(size 1.27 1.27)
				)
			)
		)
		(property "Value" ""
			(at 0 0 90)
			(layer "F.Fab")
			(effects
				(font
					(size 1.27 1.27)
				)
			)
		)
		(duplicate_pad_numbers_are_jumpers no)
		(fp_line
			(start 0.7874 -0.4064)
			(end 0.7874 0.4064)
			(stroke
				(width 0.1524)
				(type default)
			)
			(layer "F.SilkS")
		)
		(fp_line
			(start -0.7874 -0.4064)
			(end 0.7874 -0.4064)
			(stroke
				(width 0.1524)
				(type default)
			)
			(layer "F.SilkS")
		)
		(fp_line
			(start 0.7874 0.4064)
			(end -0.7874 0.4064)
			(stroke
				(width 0.1524)
				(type default)
			)
			(layer "F.SilkS")
		)
		(fp_line
			(start -0.7874 0.4064)
			(end -0.7874 -0.4064)
			(stroke
				(width 0.1524)
				(type default)
			)
			(layer "F.SilkS")
		)
		(fp_line
			(start -0.12065 -0.305054)
			(end -0.12065 -0.2794)
			(stroke
				(width 0.1)
				(type default)
			)
			(layer "F.Fab")
		)
		(fp_line
			(start -0.67945 -0.305054)
			(end -0.12065 -0.305054)
			(stroke
				(width 0.1)
				(type default)
			)
			(layer "F.Fab")
		)
		(fp_line
			(start 0.67945 -0.3048)
			(end 0.67945 0.3048)
			(stroke
				(width 0.1)
				(type default)
			)
			(layer "F.Fab")
		)
		(fp_line
			(start 0.12065 -0.3048)
			(end 0.67945 -0.3048)
			(stroke
				(width 0.1)
				(type default)
			)
			(layer "F.Fab")
		)
		(fp_line
			(start 0.12065 -0.2794)
			(end 0.12065 -0.3048)
			(stroke
				(width 0.1)
				(type default)
			)
			(layer "F.Fab")
		)
		(fp_line
			(start -0.12065 -0.2794)
			(end 0.12065 -0.2794)
			(stroke
				(width 0.1)
				(type default)
			)
			(layer "F.Fab")
		)
		(fp_line
			(start 0.120396 0.2794)
			(end -0.12065 0.2794)
			(stroke
				(width 0.1)
				(type default)
			)
			(layer "F.Fab")
		)
		(fp_line
			(start -0.12065 0.2794)
			(end -0.12065 0.3048)
			(stroke
				(width 0.1)
				(type default)
			)
			(layer "F.Fab")
		)
		(fp_line
			(start 0.67945 0.3048)
			(end 0.120396 0.3048)
			(stroke
				(width 0.1)
				(type default)
			)
			(layer "F.Fab")
		)
		(fp_line
			(start 0.120396 0.3048)
			(end 0.120396 0.2794)
			(stroke
				(width 0.1)
				(type default)
			)
			(layer "F.Fab")
		)
		(fp_line
			(start -0.12065 0.3048)
			(end -0.67945 0.3048)
			(stroke
				(width 0.1)
				(type default)
			)
			(layer "F.Fab")
		)
		(fp_line
			(start -0.67945 0.3048)
			(end -0.67945 -0.305054)
			(stroke
				(width 0.1)
				(type default)
			)
			(layer "F.Fab")
		)
		(pad "1" smd circle
			(at -0.40005 0 90)
			(size 0 0)
			(layers "F.Cu" "F.Mask" "F.Paste")
			(net "SPI_CPU0_LVC3_D1")
		)
		(pad "2" smd circle
			(at 0.40005 0 90)
			(size 0 0)
			(layers "F.Cu" "F.Mask" "F.Paste")
			(net "SPI_CPU0_LVC3_SCM_D1")
		)
	)
)
